# T6G (Grand Teton) — schematic netlist excerpt (pin names and nets, part order shuffled) for the footprints in the layout excerpt that follows; sources: Cadence DE-HDL packaged netlist, KiCad conversion of 04192023_DAF0TMB3IC0_F0TG_MB_C_brd_V02_OCP.brd

PC521_1  Q_CAP  22UF 16V 20% X6S  pkg C0805  page 225 : A = SW_P12V_AUX_PVDD11_S3_P1_FLT ; B = GND

U101  SN74LVC1G07DBVR  IC  pkg SMLF  page 34
  NC  = NC
  A  = FM_BIOS_POST_CMPLT_N
  GND  = GND
  Y  = FM_BIOS_POST_CMPLT_BUF_R1_N
  VCC  = PVDD18_S5_P0

(kicad_pcb
	(version 20260206)
	(generator "pcbnew")
	(generator_version "10.0")
	(general
		(thickness 1.6)
		(legacy_teardrops no)
	)
	(paper "A4")
	(title_block
		(title "04192023_DAF0TMB3IC0_F0TG_MB_C_brd_V02_OCP.brd")
		(comment 1 "Grand Teton / footprints 6175-6176 of 8354")
	)
	(layers
		(0 "F.Cu" signal "TOP")
		(4 "In1.Cu" signal "GND")
		(6 "In2.Cu" signal "IN1")
		(8 "In3.Cu" signal "GND1")
		(10 "In4.Cu" signal "IN2")
		(12 "In5.Cu" signal "GND2")
		(14 "In6.Cu" signal "IN3")
		(16 "In7.Cu" signal "GND3")
		(18 "In8.Cu" signal "VCC")
		(20 "In9.Cu" signal "VCC1")
		(22 "In10.Cu" signal "GND4")
		(24 "In11.Cu" signal "IN4")
		(26 "In12.Cu" signal "GND5")
		(28 "In13.Cu" signal "IN5")
		(30 "In14.Cu" signal "GND6")
		(32 "In15.Cu" signal "IN6")
		(34 "In16.Cu" signal "GND7")
		(2 "B.Cu" signal "BOTTOM")
		(9 "F.Adhes" user "F.Adhesive")
		(11 "B.Adhes" user "B.Adhesive")
		(13 "F.Paste" user "Package Geometry/Pastemask Top")
		(15 "B.Paste" user "Package Geometry/Pastemask Bottom")
		(5 "F.SilkS" user "Ref Des/Silkscreen Top")
		(7 "B.SilkS" user "Ref Des/Silkscreen Bottom")
		(1 "F.Mask" user "Board Geometry/Soldermask Top")
		(3 "B.Mask" user "Board Geometry/Soldermask Bottom")
		(17 "Dwgs.User" user "User.Drawings")
		(19 "Cmts.User" user "User.Comments")
		(21 "Eco1.User" user "User.Eco1")
		(23 "Eco2.User" user "User.Eco2")
		(25 "Edge.Cuts" user "Board Geometry/Outline")
		(27 "Margin" user)
		(31 "F.CrtYd" user "Package Geometry/Place Bound Top")
		(29 "B.CrtYd" user "Package Geometry/Place Bound Bottom")
		(35 "F.Fab" user "Ref Des/Assembly Top")
		(33 "B.Fab" user "Ref Des/Assembly Bottom")
	)
	(footprint ""
		(layer "B.Cu")
		(at 404.475696 -344.300302)
		(property "Reference" "U101"
			(at 5.969 -0.980948 0)
			(unlocked yes)
			(layer "B.SilkS")
			(effects
				(font
					(size 0.7874 0.5842)
					(thickness 0.1524)
				)
				(justify left mirror)
			)
		)
		(property "Value" ""
			(at 0 0 0)
			(layer "B.Fab")
			(effects
				(font
					(size 1.27 1.27)
				)
				(justify mirror)
			)
		)
		(duplicate_pad_numbers_are_jumpers no)
		(fp_line
			(start -2.0574 -1.651)
			(end -2.0574 1.651)
			(stroke
				(width 0.1524)
				(type default)
			)
			(layer "B.SilkS")
		)
		(fp_line
			(start -2.0574 1.651)
			(end 2.0574 1.651)
			(stroke
				(width 0.1524)
				(type default)
			)
			(layer "B.SilkS")
		)
		(fp_line
			(start -0.381 -1.651)
			(end -2.0574 -1.651)
			(stroke
				(width 0.1524)
				(type default)
			)
			(layer "B.SilkS")
		)
		(fp_line
			(start 0 -1.016)
			(end -0.381 -1.651)
			(stroke
				(width 0.1524)
				(type default)
			)
			(layer "B.SilkS")
		)
		(fp_line
			(start 0.381 -1.651)
			(end 0 -1.016)
			(stroke
				(width 0.1524)
				(type default)
			)
			(layer "B.SilkS")
		)
		(fp_line
			(start 2.0574 -1.651)
			(end 0.381 -1.651)
			(stroke
				(width 0.1524)
				(type default)
			)
			(layer "B.SilkS")
		)
		(fp_line
			(start 2.0574 1.651)
			(end 2.0574 -1.651)
			(stroke
				(width 0.1524)
				(type default)
			)
			(layer "B.SilkS")
		)
		(fp_poly
			(pts
				(xy 2.159 -1.016) (xy 2.71272 -0.719328) (xy 2.71272 -1.344168)
			)
			(stroke
				(width 0)
				(type default)
			)
			(fill yes)
			(layer "B.SilkS")
		)
		(fp_line
			(start -1.599946 -1.199896)
			(end -1.599946 1.199896)
			(stroke
				(width 0.1)
				(type default)
			)
			(layer "B.Fab")
		)
		(fp_line
			(start -1.599946 1.199896)
			(end -0.899922 1.199896)
			(stroke
				(width 0.1)
				(type default)
			)
			(layer "B.Fab")
		)
		(fp_line
			(start -0.899922 -1.549908)
			(end -0.899922 -1.199896)
			(stroke
				(width 0.1)
				(type default)
			)
			(layer "B.Fab")
		)
		(fp_line
			(start -0.899922 -1.199896)
			(end -1.599946 -1.199896)
			(stroke
				(width 0.1)
				(type default)
			)
			(layer "B.Fab")
		)
		(fp_line
			(start -0.899922 1.199896)
			(end -0.899922 1.549908)
			(stroke
				(width 0.1)
				(type default)
			)
			(layer "B.Fab")
		)
		(fp_line
			(start -0.899922 1.549908)
			(end 0.899922 1.549908)
			(stroke
				(width 0.1)
				(type default)
			)
			(layer "B.Fab")
		)
		(fp_line
			(start 0.899922 -1.549908)
			(end -0.899922 -1.549908)
			(stroke
				(width 0.1)
				(type default)
			)
			(layer "B.Fab")
		)
		(fp_line
			(start 0.899922 -1.199896)
			(end 0.899922 -1.549908)
			(stroke
				(width 0.1)
				(type default)
			)
			(layer "B.Fab")
		)
		(fp_line
			(start 0.899922 1.199896)
			(end 1.599946 1.199896)
			(stroke
				(width 0.1)
				(type default)
			)
			(layer "B.Fab")
		)
		(fp_line
			(start 0.899922 1.549908)
			(end 0.899922 1.199896)
			(stroke
				(width 0.1)
				(type default)
			)
			(layer "B.Fab")
		)
		(fp_line
			(start 1.599946 -1.199896)
			(end 0.899922 -1.199896)
			(stroke
				(width 0.1)
				(type default)
			)
			(layer "B.Fab")
		)
		(fp_line
			(start 1.599946 1.199896)
			(end 1.599946 -1.199896)
			(stroke
				(width 0.1)
				(type default)
			)
			(layer "B.Fab")
		)
		(fp_poly
			(pts
				(xy 2.71272 -0.719328) (xy 2.71272 -1.344168) (xy 2.159 -1.016)
			)
			(stroke
				(width 0)
				(type default)
			)
			(fill yes)
			(layer "B.Fab")
		)
		(pad "1" smd rect
			(at 1.225042 -0.94996 270)
			(size 0.5588 1.3462)
			(layers "B.Cu" "B.Mask" "B.Paste")
			(net "Net_10729")
		)
		(pad "2" smd rect
			(at 1.225042 0 270)
			(size 0.5588 1.3462)
			(layers "B.Cu" "B.Mask" "B.Paste")
			(net "FM_BIOS_POST_CMPLT_N")
		)
		(pad "3" smd rect
			(at 1.225042 0.94996 270)
			(size 0.5588 1.3462)
			(layers "B.Cu" "B.Mask" "B.Paste")
			(net "GND")
		)
		(pad "4" smd rect
			(at -1.225042 0.94996 270)
			(size 0.5588 1.3462)
			(layers "B.Cu" "B.Mask" "B.Paste")
			(net "FM_BIOS_POST_CMPLT_BUF_R1_N")
		)
		(pad "5" smd rect
			(at -1.225042 -0.94996 270)
			(size 0.5588 1.3462)
			(layers "B.Cu" "B.Mask" "B.Paste")
			(net "PVDD18_S5_P0")
		)
	)
	(footprint ""
		(layer "B.Cu")
		(at 185.201814 -357.667052)
		(property "Reference" "PC521_1"
			(at 0 0 0)
			(layer "B.SilkS")
			(hide yes)
			(effects
				(font
					(size 1.27 1.27)
				)
				(justify mirror)
			)
		)
		(property "Value" ""
			(at 0 0 0)
			(layer "B.Fab")
			(effects
				(font
					(size 1.27 1.27)
				)
				(justify mirror)
			)
		)
		(duplicate_pad_numbers_are_jumpers no)
		(fp_line
			(start -1.524 -0.762)
			(end -1.524 0.762)
			(stroke
				(width 0.1524)
				(type default)
			)
			(layer "B.SilkS")
		)
		(fp_line
			(start -1.524 0.762)
			(end 1.524 0.762)
			(stroke
				(width 0.1524)
				(type default)
			)
			(layer "B.SilkS")
		)
		(fp_line
			(start 1.524 -0.762)
			(end -1.524 -0.762)
			(stroke
				(width 0.1524)
				(type default)
			)
			(layer "B.SilkS")
		)
		(fp_line
			(start 1.524 0.762)
			(end 1.524 -0.762)
			(stroke
				(width 0.1524)
				(type default)
			)
			(layer "B.SilkS")
		)
		(fp_line
			(start -1.1049 -0.724916)
			(end 1.1049 -0.724916)
			(stroke
				(width 0.1)
				(type default)
			)
			(layer "B.Fab")
		)
		(fp_line
			(start -1.1049 0.724916)
			(end -1.1049 -0.724916)
			(stroke
				(width 0.1)
				(type default)
			)
			(layer "B.Fab")
		)
		(fp_line
			(start 1.1049 -0.724916)
			(end 1.1049 0.724916)
			(stroke
				(width 0.1)
				(type default)
			)
			(layer "B.Fab")
		)
		(fp_line
			(start 1.1049 0.724916)
			(end -1.1049 0.724916)
			(stroke
				(width 0.1)
				(type default)
			)
			(layer "B.Fab")
		)
		(pad "1" smd rect
			(at 0.889 0)
			(size 1.016 1.27)
			(layers "B.Cu" "B.Mask" "B.Paste")
			(net "SW_P12V_AUX_PVDD11_S3_P1_FLT")
		)
		(pad "2" smd rect
			(at -0.889 0)
			(size 1.016 1.27)
			(layers "B.Cu" "B.Mask" "B.Paste")
			(net "GND")
		)
	)
)
